# SCM (Grand Teton) — schematic netlist excerpt (pin names and nets, part order shuffled) for the footprints in the layout excerpt that follows; sources: Cadence DE-HDL packaged netlist, KiCad conversion of 12092022_DA0F0TMDCD0_F0T_Management_Board_D_brd_V3_OCP.brd

R196  Q_RES  1K 1% CHIP  pkg 0402LF  page 14 : A = P1V2_P1V0_I3C_VDDL1 ; B = I3C4_SPD_SCL
C267  Q_CAP  1UF 16V 10% EMPTY  pkg 0402  page 27 : A = LPC_ESPI_SEL_R1 ; B = GND

(kicad_pcb
	(version 20260206)
	(generator "pcbnew")
	(generator_version "10.0")
	(general
		(thickness 1.6)
		(legacy_teardrops no)
	)
	(paper "A4")
	(title_block
		(title "12092022_DA0F0TMDCD0_F0T_Management_Board_D_brd_V3_OCP.brd")
		(comment 1 "Grand Teton / footprints 928-929 of 1440")
	)
	(layers
		(0 "F.Cu" signal "TOP")
		(4 "In1.Cu" signal "GND")
		(6 "In2.Cu" signal "IN1")
		(8 "In3.Cu" signal "GND1")
		(10 "In4.Cu" signal "IN2")
		(12 "In5.Cu" signal "VCC")
		(14 "In6.Cu" signal "VCC1")
		(16 "In7.Cu" signal "IN3")
		(18 "In8.Cu" signal "GND2")
		(20 "In9.Cu" signal "IN4")
		(22 "In10.Cu" signal "GND3")
		(2 "B.Cu" signal "BOTTOM")
		(9 "F.Adhes" user "F.Adhesive")
		(11 "B.Adhes" user "B.Adhesive")
		(13 "F.Paste" user "Package Geometry/Pastemask Top")
		(15 "B.Paste" user "Package Geometry/Pastemask Bottom")
		(5 "F.SilkS" user "Ref Des/Silkscreen Top")
		(7 "B.SilkS" user "Ref Des/Silkscreen Bottom")
		(1 "F.Mask" user "Board Geometry/Soldermask Top")
		(3 "B.Mask" user "Board Geometry/Soldermask Bottom")
		(17 "Dwgs.User" user "User.Drawings")
		(19 "Cmts.User" user "User.Comments")
		(21 "Eco1.User" user "User.Eco1")
		(23 "Eco2.User" user "User.Eco2")
		(25 "Edge.Cuts" user "Board Geometry/Outline")
		(27 "Margin" user)
		(31 "F.CrtYd" user "Package Geometry/Place Bound Top")
		(29 "B.CrtYd" user "Package Geometry/Place Bound Bottom")
		(35 "F.Fab" user "Ref Des/Assembly Top")
		(33 "B.Fab" user "Ref Des/Assembly Bottom")
	)
	(footprint ""
		(layer "B.Cu")
		(at 39.868602 -63.756794 -90)
		(property "Reference" "R196"
			(at 0 0 90)
			(layer "B.SilkS")
			(hide yes)
			(effects
				(font
					(size 1.27 1.27)
				)
				(justify mirror)
			)
		)
		(property "Value" ""
			(at 0 0 90)
			(layer "B.Fab")
			(effects
				(font
					(size 1.27 1.27)
				)
				(justify mirror)
			)
		)
		(duplicate_pad_numbers_are_jumpers no)
		(fp_line
			(start -0.7874 0.4064)
			(end 0.7874 0.4064)
			(stroke
				(width 0.1524)
				(type default)
			)
			(layer "B.SilkS")
		)
		(fp_line
			(start 0.7874 0.4064)
			(end 0.7874 -0.4064)
			(stroke
				(width 0.1524)
				(type default)
			)
			(layer "B.SilkS")
		)
		(fp_line
			(start -0.7874 -0.4064)
			(end -0.7874 0.4064)
			(stroke
				(width 0.1524)
				(type default)
			)
			(layer "B.SilkS")
		)
		(fp_line
			(start 0.7874 -0.4064)
			(end -0.7874 -0.4064)
			(stroke
				(width 0.1524)
				(type default)
			)
			(layer "B.SilkS")
		)
		(fp_line
			(start -0.67945 0.3048)
			(end -0.120396 0.3048)
			(stroke
				(width 0.1)
				(type default)
			)
			(layer "B.Fab")
		)
		(fp_line
			(start -0.120396 0.3048)
			(end -0.120396 0.2794)
			(stroke
				(width 0.1)
				(type default)
			)
			(layer "B.Fab")
		)
		(fp_line
			(start 0.12065 0.3048)
			(end 0.67945 0.3048)
			(stroke
				(width 0.1)
				(type default)
			)
			(layer "B.Fab")
		)
		(fp_line
			(start 0.67945 0.3048)
			(end 0.67945 -0.305054)
			(stroke
				(width 0.1)
				(type default)
			)
			(layer "B.Fab")
		)
		(fp_line
			(start -0.120396 0.2794)
			(end 0.12065 0.2794)
			(stroke
				(width 0.1)
				(type default)
			)
			(layer "B.Fab")
		)
		(fp_line
			(start 0.12065 0.2794)
			(end 0.12065 0.3048)
			(stroke
				(width 0.1)
				(type default)
			)
			(layer "B.Fab")
		)
		(fp_line
			(start -0.12065 -0.2794)
			(end -0.12065 -0.3048)
			(stroke
				(width 0.1)
				(type default)
			)
			(layer "B.Fab")
		)
		(fp_line
			(start 0.12065 -0.2794)
			(end -0.12065 -0.2794)
			(stroke
				(width 0.1)
				(type default)
			)
			(layer "B.Fab")
		)
		(fp_line
			(start -0.67945 -0.3048)
			(end -0.67945 0.3048)
			(stroke
				(width 0.1)
				(type default)
			)
			(layer "B.Fab")
		)
		(fp_line
			(start -0.12065 -0.3048)
			(end -0.67945 -0.3048)
			(stroke
				(width 0.1)
				(type default)
			)
			(layer "B.Fab")
		)
		(fp_line
			(start 0.12065 -0.305054)
			(end 0.12065 -0.2794)
			(stroke
				(width 0.1)
				(type default)
			)
			(layer "B.Fab")
		)
		(fp_line
			(start 0.67945 -0.305054)
			(end 0.12065 -0.305054)
			(stroke
				(width 0.1)
				(type default)
			)
			(layer "B.Fab")
		)
		(pad "1" smd circle
			(at 0.40005 0 90)
			(size 0 0)
			(layers "B.Cu" "B.Mask" "B.Paste")
			(net "P1V2_P1V0_I3C_VDDL1")
		)
		(pad "2" smd circle
			(at -0.40005 0 90)
			(size 0 0)
			(layers "B.Cu" "B.Mask" "B.Paste")
			(net "I3C4_SPD_SCL")
		)
	)
	(footprint ""
		(layer "B.Cu")
		(at 74.095356 -100.93071 180)
		(property "Reference" "C267"
			(at 0 0 0)
			(layer "B.SilkS")
			(hide yes)
			(effects
				(font
					(size 1.27 1.27)
				)
				(justify mirror)
			)
		)
		(property "Value" ""
			(at 0 0 0)
			(layer "B.Fab")
			(effects
				(font
					(size 1.27 1.27)
				)
				(justify mirror)
			)
		)
		(duplicate_pad_numbers_are_jumpers no)
		(fp_line
			(start 0.7874 0.4064)
			(end 0.7874 -0.4064)
			(stroke
				(width 0.1524)
				(type default)
			)
			(layer "B.SilkS")
		)
		(fp_line
			(start 0.7874 -0.4064)
			(end -0.7874 -0.4064)
			(stroke
				(width 0.1524)
				(type default)
			)
			(layer "B.SilkS")
		)
		(fp_line
			(start -0.7874 0.4064)
			(end 0.7874 0.4064)
			(stroke
				(width 0.1524)
				(type default)
			)
			(layer "B.SilkS")
		)
		(fp_line
			(start -0.7874 -0.4064)
			(end -0.7874 0.4064)
			(stroke
				(width 0.1524)
				(type default)
			)
			(layer "B.SilkS")
		)
		(fp_line
			(start 0.67945 0.3048)
			(end 0.67945 -0.305054)
			(stroke
				(width 0.1)
				(type default)
			)
			(layer "B.Fab")
		)
		(fp_line
			(start 0.67945 -0.305054)
			(end 0.12065 -0.305054)
			(stroke
				(width 0.1)
				(type default)
			)
			(layer "B.Fab")
		)
		(fp_line
			(start 0.12065 0.3048)
			(end 0.67945 0.3048)
			(stroke
				(width 0.1)
				(type default)
			)
			(layer "B.Fab")
		)
		(fp_line
			(start 0.12065 0.2794)
			(end 0.12065 0.3048)
			(stroke
				(width 0.1)
				(type default)
			)
			(layer "B.Fab")
		)
		(fp_line
			(start 0.12065 -0.2794)
			(end -0.12065 -0.2794)
			(stroke
				(width 0.1)
				(type default)
			)
			(layer "B.Fab")
		)
		(fp_line
			(start 0.12065 -0.305054)
			(end 0.12065 -0.2794)
			(stroke
				(width 0.1)
				(type default)
			)
			(layer "B.Fab")
		)
		(fp_line
			(start -0.120396 0.3048)
			(end -0.120396 0.2794)
			(stroke
				(width 0.1)
				(type default)
			)
			(layer "B.Fab")
		)
		(fp_line
			(start -0.120396 0.2794)
			(end 0.12065 0.2794)
			(stroke
				(width 0.1)
				(type default)
			)
			(layer "B.Fab")
		)
		(fp_line
			(start -0.12065 -0.2794)
			(end -0.12065 -0.3048)
			(stroke
				(width 0.1)
				(type default)
			)
			(layer "B.Fab")
		)
		(fp_line
			(start -0.12065 -0.3048)
			(end -0.67945 -0.3048)
			(stroke
				(width 0.1)
				(type default)
			)
			(layer "B.Fab")
		)
		(fp_line
			(start -0.67945 0.3048)
			(end -0.120396 0.3048)
			(stroke
				(width 0.1)
				(type default)
			)
			(layer "B.Fab")
		)
		(fp_line
			(start -0.67945 -0.3048)
			(end -0.67945 0.3048)
			(stroke
				(width 0.1)
				(type default)
			)
			(layer "B.Fab")
		)
		(pad "1" smd circle
			(at 0.40005 0)
			(size 0 0)
			(layers "B.Cu" "B.Mask" "B.Paste")
			(net "LPC_ESPI_SEL_R1")
		)
		(pad "2" smd circle
			(at -0.40005 0)
			(size 0 0)
			(layers "B.Cu" "B.Mask" "B.Paste")
			(net "GND")
		)
	)
)
